(kicad_pcb
	(version 20260206)
	(generator "pcbnew")
	(generator_version "10.0")
	(general
		(thickness 1.6)
		(legacy_teardrops no)
	)
	(paper "A4")
	(title_block
		(title "01162023_DA0F0TEBIF0_F0T_Expander_BD_F_brd_V02_OCP.brd")
		(comment 1 "Grand Teton / footprints 5340-5344 of 9728")
	)
	(layers
		(0 "F.Cu" signal "TOP")
		(4 "In1.Cu" signal "GND")
		(6 "In2.Cu" signal "VCC")
		(8 "In3.Cu" signal "VCC1")
		(10 "In4.Cu" signal "GND1")
		(12 "In5.Cu" signal "IN1")
		(14 "In6.Cu" signal "GND2")
		(16 "In7.Cu" signal "IN2")
		(18 "In8.Cu" signal "GND3")
		(20 "In9.Cu" signal "IN3")
		(22 "In10.Cu" signal "GND4")
		(24 "In11.Cu" signal "IN4")
		(26 "In12.Cu" signal "GND5")
		(28 "In13.Cu" signal "IN5")
		(30 "In14.Cu" signal "GND6")
		(32 "In15.Cu" signal "IN6")
		(34 "In16.Cu" signal "GND7")
		(2 "B.Cu" signal "BOTTOM")
		(9 "F.Adhes" user "F.Adhesive")
		(11 "B.Adhes" user "B.Adhesive")
		(13 "F.Paste" user "Package Geometry/Pastemask Top")
		(15 "B.Paste" user "Package Geometry/Pastemask Bottom")
		(5 "F.SilkS" user "Ref Des/Silkscreen Top")
		(7 "B.SilkS" user "Ref Des/Silkscreen Bottom")
		(1 "F.Mask" user "Board Geometry/Soldermask Top")
		(3 "B.Mask" user "Board Geometry/Soldermask Bottom")
		(17 "Dwgs.User" user "User.Drawings")
		(19 "Cmts.User" user "User.Comments")
		(21 "Eco1.User" user "User.Eco1")
		(23 "Eco2.User" user "User.Eco2")
		(25 "Edge.Cuts" user "Board Geometry/Outline")
		(27 "Margin" user)
		(31 "F.CrtYd" user "Package Geometry/Place Bound Top")
		(29 "B.CrtYd" user "Package Geometry/Place Bound Bottom")
		(35 "F.Fab" user "Ref Des/Assembly Top")
		(33 "B.Fab" user "Ref Des/Assembly Bottom")
	)
	(footprint ""
		(layer "F.Cu")
		(at 32.411416 -280.443432 -90)
		(property "Reference" "R4566"
			(at 0 0 270)
			(layer "F.SilkS")
			(hide yes)
			(effects
				(font
					(size 1.27 1.27)
				)
			)
		)
		(property "Value" ""
			(at 0 0 270)
			(layer "F.Fab")
			(effects
				(font
					(size 1.27 1.27)
				)
			)
		)
		(duplicate_pad_numbers_are_jumpers no)
		(fp_line
			(start -0.7874 0.4064)
			(end -0.7874 -0.4064)
			(stroke
				(width 0.1524)
				(type default)
			)
			(layer "F.SilkS")
		)
		(fp_line
			(start 0.7874 0.4064)
			(end -0.7874 0.4064)
			(stroke
				(width 0.1524)
				(type default)
			)
			(layer "F.SilkS")
		)
		(fp_line
			(start -0.7874 -0.4064)
			(end 0.7874 -0.4064)
			(stroke
				(width 0.1524)
				(type default)
			)
			(layer "F.SilkS")
		)
		(fp_line
			(start 0.7874 -0.4064)
			(end 0.7874 0.4064)
			(stroke
				(width 0.1524)
				(type default)
			)
			(layer "F.SilkS")
		)
		(fp_line
			(start -0.67945 0.3048)
			(end -0.67945 -0.305054)
			(stroke
				(width 0.1)
				(type default)
			)
			(layer "F.Fab")
		)
		(fp_line
			(start -0.12065 0.3048)
			(end -0.67945 0.3048)
			(stroke
				(width 0.1)
				(type default)
			)
			(layer "F.Fab")
		)
		(fp_line
			(start 0.120396 0.3048)
			(end 0.120396 0.2794)
			(stroke
				(width 0.1)
				(type default)
			)
			(layer "F.Fab")
		)
		(fp_line
			(start 0.67945 0.3048)
			(end 0.120396 0.3048)
			(stroke
				(width 0.1)
				(type default)
			)
			(layer "F.Fab")
		)
		(fp_line
			(start -0.12065 0.2794)
			(end -0.12065 0.3048)
			(stroke
				(width 0.1)
				(type default)
			)
			(layer "F.Fab")
		)
		(fp_line
			(start 0.120396 0.2794)
			(end -0.12065 0.2794)
			(stroke
				(width 0.1)
				(type default)
			)
			(layer "F.Fab")
		)
		(fp_line
			(start -0.12065 -0.2794)
			(end 0.12065 -0.2794)
			(stroke
				(width 0.1)
				(type default)
			)
			(layer "F.Fab")
		)
		(fp_line
			(start 0.12065 -0.2794)
			(end 0.12065 -0.3048)
			(stroke
				(width 0.1)
				(type default)
			)
			(layer "F.Fab")
		)
		(fp_line
			(start 0.12065 -0.3048)
			(end 0.67945 -0.3048)
			(stroke
				(width 0.1)
				(type default)
			)
			(layer "F.Fab")
		)
		(fp_line
			(start 0.67945 -0.3048)
			(end 0.67945 0.3048)
			(stroke
				(width 0.1)
				(type default)
			)
			(layer "F.Fab")
		)
		(fp_line
			(start -0.67945 -0.305054)
			(end -0.12065 -0.305054)
			(stroke
				(width 0.1)
				(type default)
			)
			(layer "F.Fab")
		)
		(fp_line
			(start -0.12065 -0.305054)
			(end -0.12065 -0.2794)
			(stroke
				(width 0.1)
				(type default)
			)
			(layer "F.Fab")
		)
		(pad "1" smd circle
			(at -0.40005 0 270)
			(size 0 0)
			(layers "F.Cu" "F.Mask" "F.Paste")
			(net "SYSPLL_VDDA18_PEX0")
		)
		(pad "2" smd circle
			(at 0.40005 0 270)
			(size 0 0)
			(layers "F.Cu" "F.Mask" "F.Paste")
			(net "SYSPLL_VDDA18_PEX0_R")
		)
	)
	(footprint ""
		(layer "F.Cu")
		(at 102.353364 -224.249996 90)
		(property "Reference" "PR187"
			(at 0 0 90)
			(layer "F.SilkS")
			(hide yes)
			(effects
				(font
					(size 1.27 1.27)
				)
			)
		)
		(property "Value" ""
			(at 0 0 90)
			(layer "F.Fab")
			(effects
				(font
					(size 1.27 1.27)
				)
			)
		)
		(duplicate_pad_numbers_are_jumpers no)
		(fp_line
			(start 0.7874 -0.4064)
			(end 0.7874 0.4064)
			(stroke
				(width 0.1524)
				(type default)
			)
			(layer "F.SilkS")
		)
		(fp_line
			(start -0.7874 -0.4064)
			(end 0.7874 -0.4064)
			(stroke
				(width 0.1524)
				(type default)
			)
			(layer "F.SilkS")
		)
		(fp_line
			(start 0.7874 0.4064)
			(end -0.7874 0.4064)
			(stroke
				(width 0.1524)
				(type default)
			)
			(layer "F.SilkS")
		)
		(fp_line
			(start -0.7874 0.4064)
			(end -0.7874 -0.4064)
			(stroke
				(width 0.1524)
				(type default)
			)
			(layer "F.SilkS")
		)
		(fp_line
			(start -0.12065 -0.305054)
			(end -0.12065 -0.2794)
			(stroke
				(width 0.1)
				(type default)
			)
			(layer "F.Fab")
		)
		(fp_line
			(start -0.67945 -0.305054)
			(end -0.12065 -0.305054)
			(stroke
				(width 0.1)
				(type default)
			)
			(layer "F.Fab")
		)
		(fp_line
			(start 0.67945 -0.3048)
			(end 0.67945 0.3048)
			(stroke
				(width 0.1)
				(type default)
			)
			(layer "F.Fab")
		)
		(fp_line
			(start 0.12065 -0.3048)
			(end 0.67945 -0.3048)
			(stroke
				(width 0.1)
				(type default)
			)
			(layer "F.Fab")
		)
		(fp_line
			(start 0.12065 -0.2794)
			(end 0.12065 -0.3048)
			(stroke
				(width 0.1)
				(type default)
			)
			(layer "F.Fab")
		)
		(fp_line
			(start -0.12065 -0.2794)
			(end 0.12065 -0.2794)
			(stroke
				(width 0.1)
				(type default)
			)
			(layer "F.Fab")
		)
		(fp_line
			(start 0.120396 0.2794)
			(end -0.12065 0.2794)
			(stroke
				(width 0.1)
				(type default)
			)
			(layer "F.Fab")
		)
		(fp_line
			(start -0.12065 0.2794)
			(end -0.12065 0.3048)
			(stroke
				(width 0.1)
				(type default)
			)
			(layer "F.Fab")
		)
		(fp_line
			(start 0.67945 0.3048)
			(end 0.120396 0.3048)
			(stroke
				(width 0.1)
				(type default)
			)
			(layer "F.Fab")
		)
		(fp_line
			(start 0.120396 0.3048)
			(end 0.120396 0.2794)
			(stroke
				(width 0.1)
				(type default)
			)
			(layer "F.Fab")
		)
		(fp_line
			(start -0.12065 0.3048)
			(end -0.67945 0.3048)
			(stroke
				(width 0.1)
				(type default)
			)
			(layer "F.Fab")
		)
		(fp_line
			(start -0.67945 0.3048)
			(end -0.67945 -0.305054)
			(stroke
				(width 0.1)
				(type default)
			)
			(layer "F.Fab")
		)
		(pad "1" smd circle
			(at -0.40005 0 90)
			(size 0 0)
			(layers "F.Cu" "F.Mask" "F.Paste")
			(net "P1V8_PEX_CS")
		)
		(pad "2" smd circle
			(at 0.40005 0 90)
			(size 0 0)
			(layers "F.Cu" "F.Mask" "F.Paste")
			(net "GND")
		)
	)
	(footprint ""
		(layer "F.Cu")
		(at 83.034124 -5.030724)
		(property "Reference" "R5806"
			(at 0 0 0)
			(layer "F.SilkS")
			(hide yes)
			(effects
				(font
					(size 1.27 1.27)
				)
			)
		)
		(property "Value" ""
			(at 0 0 0)
			(layer "F.Fab")
			(effects
				(font
					(size 1.27 1.27)
				)
			)
		)
		(duplicate_pad_numbers_are_jumpers no)
		(fp_line
			(start -0.7874 -0.4064)
			(end 0.7874 -0.4064)
			(stroke
				(width 0.1524)
				(type default)
			)
			(layer "F.SilkS")
		)
		(fp_line
			(start -0.7874 0.4064)
			(end -0.7874 -0.4064)
			(stroke
				(width 0.1524)
				(type default)
			)
			(layer "F.SilkS")
		)
		(fp_line
			(start 0.7874 -0.4064)
			(end 0.7874 0.4064)
			(stroke
				(width 0.1524)
				(type default)
			)
			(layer "F.SilkS")
		)
		(fp_line
			(start 0.7874 0.4064)
			(end -0.7874 0.4064)
			(stroke
				(width 0.1524)
				(type default)
			)
			(layer "F.SilkS")
		)
		(fp_line
			(start -0.67945 -0.305054)
			(end -0.12065 -0.305054)
			(stroke
				(width 0.1)
				(type default)
			)
			(layer "F.Fab")
		)
		(fp_line
			(start -0.67945 0.3048)
			(end -0.67945 -0.305054)
			(stroke
				(width 0.1)
				(type default)
			)
			(layer "F.Fab")
		)
		(fp_line
			(start -0.12065 -0.305054)
			(end -0.12065 -0.2794)
			(stroke
				(width 0.1)
				(type default)
			)
			(layer "F.Fab")
		)
		(fp_line
			(start -0.12065 -0.2794)
			(end 0.12065 -0.2794)
			(stroke
				(width 0.1)
				(type default)
			)
			(layer "F.Fab")
		)
		(fp_line
			(start -0.12065 0.2794)
			(end -0.12065 0.3048)
			(stroke
				(width 0.1)
				(type default)
			)
			(layer "F.Fab")
		)
		(fp_line
			(start -0.12065 0.3048)
			(end -0.67945 0.3048)
			(stroke
				(width 0.1)
				(type default)
			)
			(layer "F.Fab")
		)
		(fp_line
			(start 0.120396 0.2794)
			(end -0.12065 0.2794)
			(stroke
				(width 0.1)
				(type default)
			)
			(layer "F.Fab")
		)
		(fp_line
			(start 0.120396 0.3048)
			(end 0.120396 0.2794)
			(stroke
				(width 0.1)
				(type default)
			)
			(layer "F.Fab")
		)
		(fp_line
			(start 0.12065 -0.3048)
			(end 0.67945 -0.3048)
			(stroke
				(width 0.1)
				(type default)
			)
			(layer "F.Fab")
		)
		(fp_line
			(start 0.12065 -0.2794)
			(end 0.12065 -0.3048)
			(stroke
				(width 0.1)
				(type default)
			)
			(layer "F.Fab")
		)
		(fp_line
			(start 0.67945 -0.3048)
			(end 0.67945 0.3048)
			(stroke
				(width 0.1)
				(type default)
			)
			(layer "F.Fab")
		)
		(fp_line
			(start 0.67945 0.3048)
			(end 0.120396 0.3048)
			(stroke
				(width 0.1)
				(type default)
			)
			(layer "F.Fab")
		)
		(pad "1" smd circle
			(at -0.40005 0)
			(size 0 0)
			(layers "F.Cu" "F.Mask" "F.Paste")
			(net "LM75_2_A1")
		)
		(pad "2" smd circle
			(at 0.40005 0)
			(size 0 0)
			(layers "F.Cu" "F.Mask" "F.Paste")
			(net "P3V3_AUX")
		)
	)
	(footprint ""
		(layer "F.Cu")
		(at 328.83856 -22.867366 90)
		(property "Reference" "C3953"
			(at 0 0 90)
			(layer "F.SilkS")
			(hide yes)
			(effects
				(font
					(size 1.27 1.27)
				)
			)
		)
		(property "Value" ""
			(at 0 0 90)
			(layer "F.Fab")
			(effects
				(font
					(size 1.27 1.27)
				)
			)
		)
		(duplicate_pad_numbers_are_jumpers no)
		(fp_line
			(start 0.7874 -0.4064)
			(end 0.7874 0.4064)
			(stroke
				(width 0.1524)
				(type default)
			)
			(layer "F.SilkS")
		)
		(fp_line
			(start -0.7874 -0.4064)
			(end 0.7874 -0.4064)
			(stroke
				(width 0.1524)
				(type default)
			)
			(layer "F.SilkS")
		)
		(fp_line
			(start 0.7874 0.4064)
			(end -0.7874 0.4064)
			(stroke
				(width 0.1524)
				(type default)
			)
			(layer "F.SilkS")
		)
		(fp_line
			(start -0.7874 0.4064)
			(end -0.7874 -0.4064)
			(stroke
				(width 0.1524)
				(type default)
			)
			(layer "F.SilkS")
		)
		(fp_line
			(start -0.12065 -0.305054)
			(end -0.12065 -0.2794)
			(stroke
				(width 0.1)
				(type default)
			)
			(layer "F.Fab")
		)
		(fp_line
			(start -0.67945 -0.305054)
			(end -0.12065 -0.305054)
			(stroke
				(width 0.1)
				(type default)
			)
			(layer "F.Fab")
		)
		(fp_line
			(start 0.67945 -0.3048)
			(end 0.67945 0.3048)
			(stroke
				(width 0.1)
				(type default)
			)
			(layer "F.Fab")
		)
		(fp_line
			(start 0.12065 -0.3048)
			(end 0.67945 -0.3048)
			(stroke
				(width 0.1)
				(type default)
			)
			(layer "F.Fab")
		)
		(fp_line
			(start 0.12065 -0.2794)
			(end 0.12065 -0.3048)
			(stroke
				(width 0.1)
				(type default)
			)
			(layer "F.Fab")
		)
		(fp_line
			(start -0.12065 -0.2794)
			(end 0.12065 -0.2794)
			(stroke
				(width 0.1)
				(type default)
			)
			(layer "F.Fab")
		)
		(fp_line
			(start 0.120396 0.2794)
			(end -0.12065 0.2794)
			(stroke
				(width 0.1)
				(type default)
			)
			(layer "F.Fab")
		)
		(fp_line
			(start -0.12065 0.2794)
			(end -0.12065 0.3048)
			(stroke
				(width 0.1)
				(type default)
			)
			(layer "F.Fab")
		)
		(fp_line
			(start 0.67945 0.3048)
			(end 0.120396 0.3048)
			(stroke
				(width 0.1)
				(type default)
			)
			(layer "F.Fab")
		)
		(fp_line
			(start 0.120396 0.3048)
			(end 0.120396 0.2794)
			(stroke
				(width 0.1)
				(type default)
			)
			(layer "F.Fab")
		)
		(fp_line
			(start -0.12065 0.3048)
			(end -0.67945 0.3048)
			(stroke
				(width 0.1)
				(type default)
			)
			(layer "F.Fab")
		)
		(fp_line
			(start -0.67945 0.3048)
			(end -0.67945 -0.305054)
			(stroke
				(width 0.1)
				(type default)
			)
			(layer "F.Fab")
		)
		(pad "1" smd circle
			(at -0.40005 0 90)
			(size 0 0)
			(layers "F.Cu" "F.Mask" "F.Paste")
			(net "P12V_SSD11")
		)
		(pad "2" smd circle
			(at 0.40005 0 90)
			(size 0 0)
			(layers "F.Cu" "F.Mask" "F.Paste")
			(net "GND")
		)
	)
	(footprint ""
		(layer "F.Cu")
		(at 130.454654 -303.698402 90)
		(property "Reference" "PC105"
			(at 0 0 90)
			(layer "F.SilkS")
			(hide yes)
			(effects
				(font
					(size 1.27 1.27)
				)
			)
		)
		(property "Value" ""
			(at 0 0 90)
			(layer "F.Fab")
			(effects
				(font
					(size 1.27 1.27)
				)
			)
		)
		(duplicate_pad_numbers_are_jumpers no)
		(fp_line
			(start -4.53898 -2.150618)
			(end -4.539742 2.152142)
			(stroke
				(width 0.1524)
				(type default)
			)
			(layer "F.SilkS")
		)
		(fp_line
			(start -4.69138 -2.150618)
			(end -4.692396 2.161032)
			(stroke
				(width 0.1524)
				(type default)
			)
			(layer "F.SilkS")
		)
		(fp_line
			(start -4.84378 -2.150618)
			(end -4.53898 -2.150618)
			(stroke
				(width 0.1524)
				(type default)
			)
			(layer "F.SilkS")
		)
		(fp_line
			(start -4.84378 -2.150618)
			(end -4.842256 2.163064)
			(stroke
				(width 0.1524)
				(type default)
			)
			(layer "F.SilkS")
		)
		(fp_line
			(start 4.53898 -2.15011)
			(end 4.53898 2.15011)
			(stroke
				(width 0.1524)
				(type default)
			)
			(layer "F.SilkS")
		)
		(fp_line
			(start -4.53898 -2.15011)
			(end 4.53898 -2.15011)
			(stroke
				(width 0.1524)
				(type default)
			)
			(layer "F.SilkS")
		)
		(fp_line
			(start 4.53898 2.15011)
			(end -4.53898 2.15011)
			(stroke
				(width 0.1524)
				(type default)
			)
			(layer "F.SilkS")
		)
		(fp_line
			(start -4.53898 2.15011)
			(end -4.53898 -2.15011)
			(stroke
				(width 0.1524)
				(type default)
			)
			(layer "F.SilkS")
		)
		(fp_line
			(start -4.83108 2.150364)
			(end -4.447794 2.149348)
			(stroke
				(width 0.1524)
				(type default)
			)
			(layer "F.SilkS")
		)
		(fp_line
			(start 3.64998 -2.15011)
			(end 3.64998 2.15011)
			(stroke
				(width 0.1)
				(type default)
			)
			(layer "F.Fab")
		)
		(fp_line
			(start -3.64998 -2.15011)
			(end 3.64998 -2.15011)
			(stroke
				(width 0.1)
				(type default)
			)
			(layer "F.Fab")
		)
		(fp_line
			(start 3.64998 2.15011)
			(end -3.64998 2.15011)
			(stroke
				(width 0.1)
				(type default)
			)
			(layer "F.Fab")
		)
		(fp_line
			(start -3.64998 2.15011)
			(end -3.64998 -2.15011)
			(stroke
				(width 0.1)
				(type default)
			)
			(layer "F.Fab")
		)
		(fp_text user "+"
			(at -5.027422 -3.06959 90)
			(unlocked yes)
			(layer "F.SilkS")
			(effects
				(font
					(size 1.905 1.4224)
					(thickness 0.1524)
				)
				(justify left)
			)
		)
		(fp_text user "-"
			(at 3.295396 -2.751836 90)
			(unlocked yes)
			(layer "F.SilkS")
			(effects
				(font
					(size 1.905 1.4224)
					(thickness 0.1524)
				)
				(justify left)
			)
		)
		(fp_text user "+"
			(at -6.214872 -0.337058 90)
			(unlocked yes)
			(layer "F.Fab")
			(effects
				(font
					(size 1.905 1.4224)
					(thickness 0.1524)
				)
				(justify left)
			)
		)
		(fp_text user "-"
			(at 4.313174 -0.094488 90)
			(unlocked yes)
			(layer "F.Fab")
			(effects
				(font
					(size 1.905 1.4224)
					(thickness 0.1524)
				)
				(justify left)
			)
		)
		(pad "1" smd rect
			(at -3.199892 0 90)
			(size 2.413 2.8194)
			(layers "F.Cu" "F.Mask" "F.Paste")
			(net "P0V8_PEX1")
		)
		(pad "2" smd rect
			(at 3.199892 0 90)
			(size 2.413 2.8194)
			(layers "F.Cu" "F.Mask" "F.Paste")
			(net "GND")
		)
	)
)
